# T6G (Grand Teton) — schematic netlist excerpt (pin names and nets, part order shuffled) for the footprints in the layout excerpt that follows; sources: Cadence DE-HDL packaged netlist, KiCad conversion of 04192023_DAF0TMB3IC0_F0TG_MB_C_brd_V02_OCP.brd

C2552  Q_CAP  22UF 4V 20% X6S  pkg C0402  page 70 : A = PVDDCR_SOC_P0 ; B = GND
R1684  Q_RES  10 1% CHIP  pkg 0402LF  page 95 : A = I3C_SPD_DDRGL_CPU0_SDA ; B = I3C_SPD_DDRJ_CPU0_SDA

(kicad_pcb
	(version 20260206)
	(generator "pcbnew")
	(generator_version "10.0")
	(general
		(thickness 1.6)
		(legacy_teardrops no)
	)
	(paper "A4")
	(title_block
		(title "04192023_DAF0TMB3IC0_F0TG_MB_C_brd_V02_OCP.brd")
		(comment 1 "Grand Teton / footprints 7057-7058 of 8354")
	)
	(layers
		(0 "F.Cu" signal "TOP")
		(4 "In1.Cu" signal "GND")
		(6 "In2.Cu" signal "IN1")
		(8 "In3.Cu" signal "GND1")
		(10 "In4.Cu" signal "IN2")
		(12 "In5.Cu" signal "GND2")
		(14 "In6.Cu" signal "IN3")
		(16 "In7.Cu" signal "GND3")
		(18 "In8.Cu" signal "VCC")
		(20 "In9.Cu" signal "VCC1")
		(22 "In10.Cu" signal "GND4")
		(24 "In11.Cu" signal "IN4")
		(26 "In12.Cu" signal "GND5")
		(28 "In13.Cu" signal "IN5")
		(30 "In14.Cu" signal "GND6")
		(32 "In15.Cu" signal "IN6")
		(34 "In16.Cu" signal "GND7")
		(2 "B.Cu" signal "BOTTOM")
		(9 "F.Adhes" user "F.Adhesive")
		(11 "B.Adhes" user "B.Adhesive")
		(13 "F.Paste" user "Package Geometry/Pastemask Top")
		(15 "B.Paste" user "Package Geometry/Pastemask Bottom")
		(5 "F.SilkS" user "Ref Des/Silkscreen Top")
		(7 "B.SilkS" user "Ref Des/Silkscreen Bottom")
		(1 "F.Mask" user "Board Geometry/Soldermask Top")
		(3 "B.Mask" user "Board Geometry/Soldermask Bottom")
		(17 "Dwgs.User" user "User.Drawings")
		(19 "Cmts.User" user "User.Comments")
		(21 "Eco1.User" user "User.Eco1")
		(23 "Eco2.User" user "User.Eco2")
		(25 "Edge.Cuts" user "Board Geometry/Outline")
		(27 "Margin" user)
		(31 "F.CrtYd" user "Package Geometry/Place Bound Top")
		(29 "B.CrtYd" user "Package Geometry/Place Bound Bottom")
		(35 "F.Fab" user "Ref Des/Assembly Top")
		(33 "B.Fab" user "Ref Des/Assembly Bottom")
	)
	(footprint ""
		(layer "B.Cu")
		(at 365.835692 -259.355082)
		(property "Reference" "C2552"
			(at 0 0 0)
			(layer "B.SilkS")
			(hide yes)
			(effects
				(font
					(size 1.27 1.27)
				)
				(justify mirror)
			)
		)
		(property "Value" ""
			(at 0 0 0)
			(layer "B.Fab")
			(effects
				(font
					(size 1.27 1.27)
				)
				(justify mirror)
			)
		)
		(duplicate_pad_numbers_are_jumpers no)
		(fp_line
			(start -0.7874 -0.4064)
			(end -0.7874 0.4064)
			(stroke
				(width 0.1524)
				(type default)
			)
			(layer "B.SilkS")
		)
		(fp_line
			(start -0.7874 0.4064)
			(end 0.7874 0.4064)
			(stroke
				(width 0.1524)
				(type default)
			)
			(layer "B.SilkS")
		)
		(fp_line
			(start 0.7874 -0.4064)
			(end -0.7874 -0.4064)
			(stroke
				(width 0.1524)
				(type default)
			)
			(layer "B.SilkS")
		)
		(fp_line
			(start 0.7874 0.4064)
			(end 0.7874 -0.4064)
			(stroke
				(width 0.1524)
				(type default)
			)
			(layer "B.SilkS")
		)
		(fp_line
			(start -0.67945 -0.3048)
			(end -0.67945 0.3048)
			(stroke
				(width 0.1)
				(type default)
			)
			(layer "B.Fab")
		)
		(fp_line
			(start -0.67945 0.3048)
			(end -0.120396 0.3048)
			(stroke
				(width 0.1)
				(type default)
			)
			(layer "B.Fab")
		)
		(fp_line
			(start -0.12065 -0.3048)
			(end -0.67945 -0.3048)
			(stroke
				(width 0.1)
				(type default)
			)
			(layer "B.Fab")
		)
		(fp_line
			(start -0.12065 -0.2794)
			(end -0.12065 -0.3048)
			(stroke
				(width 0.1)
				(type default)
			)
			(layer "B.Fab")
		)
		(fp_line
			(start -0.120396 0.2794)
			(end 0.12065 0.2794)
			(stroke
				(width 0.1)
				(type default)
			)
			(layer "B.Fab")
		)
		(fp_line
			(start -0.120396 0.3048)
			(end -0.120396 0.2794)
			(stroke
				(width 0.1)
				(type default)
			)
			(layer "B.Fab")
		)
		(fp_line
			(start 0.12065 -0.305054)
			(end 0.12065 -0.2794)
			(stroke
				(width 0.1)
				(type default)
			)
			(layer "B.Fab")
		)
		(fp_line
			(start 0.12065 -0.2794)
			(end -0.12065 -0.2794)
			(stroke
				(width 0.1)
				(type default)
			)
			(layer "B.Fab")
		)
		(fp_line
			(start 0.12065 0.2794)
			(end 0.12065 0.3048)
			(stroke
				(width 0.1)
				(type default)
			)
			(layer "B.Fab")
		)
		(fp_line
			(start 0.12065 0.3048)
			(end 0.67945 0.3048)
			(stroke
				(width 0.1)
				(type default)
			)
			(layer "B.Fab")
		)
		(fp_line
			(start 0.67945 -0.305054)
			(end 0.12065 -0.305054)
			(stroke
				(width 0.1)
				(type default)
			)
			(layer "B.Fab")
		)
		(fp_line
			(start 0.67945 0.3048)
			(end 0.67945 -0.305054)
			(stroke
				(width 0.1)
				(type default)
			)
			(layer "B.Fab")
		)
		(pad "1" smd circle
			(at 0.40005 0 180)
			(size 0 0)
			(layers "B.Cu" "B.Mask" "B.Paste")
			(net "PVDDCR_SOC_P0")
		)
		(pad "2" smd circle
			(at -0.40005 0 180)
			(size 0 0)
			(layers "B.Cu" "B.Mask" "B.Paste")
			(net "GND")
		)
	)
	(footprint ""
		(layer "B.Cu")
		(at 438.344564 -195.859146 180)
		(property "Reference" "R1684"
			(at 0 0 0)
			(layer "B.SilkS")
			(hide yes)
			(effects
				(font
					(size 1.27 1.27)
				)
				(justify mirror)
			)
		)
		(property "Value" ""
			(at 0 0 0)
			(layer "B.Fab")
			(effects
				(font
					(size 1.27 1.27)
				)
				(justify mirror)
			)
		)
		(duplicate_pad_numbers_are_jumpers no)
		(fp_line
			(start 0.7874 0.4064)
			(end 0.7874 -0.4064)
			(stroke
				(width 0.1524)
				(type default)
			)
			(layer "B.SilkS")
		)
		(fp_line
			(start 0.7874 -0.4064)
			(end -0.7874 -0.4064)
			(stroke
				(width 0.1524)
				(type default)
			)
			(layer "B.SilkS")
		)
		(fp_line
			(start -0.7874 0.4064)
			(end 0.7874 0.4064)
			(stroke
				(width 0.1524)
				(type default)
			)
			(layer "B.SilkS")
		)
		(fp_line
			(start -0.7874 -0.4064)
			(end -0.7874 0.4064)
			(stroke
				(width 0.1524)
				(type default)
			)
			(layer "B.SilkS")
		)
		(fp_line
			(start 0.67945 0.3048)
			(end 0.67945 -0.305054)
			(stroke
				(width 0.1)
				(type default)
			)
			(layer "B.Fab")
		)
		(fp_line
			(start 0.67945 -0.305054)
			(end 0.12065 -0.305054)
			(stroke
				(width 0.1)
				(type default)
			)
			(layer "B.Fab")
		)
		(fp_line
			(start 0.12065 0.3048)
			(end 0.67945 0.3048)
			(stroke
				(width 0.1)
				(type default)
			)
			(layer "B.Fab")
		)
		(fp_line
			(start 0.12065 0.2794)
			(end 0.12065 0.3048)
			(stroke
				(width 0.1)
				(type default)
			)
			(layer "B.Fab")
		)
		(fp_line
			(start 0.12065 -0.2794)
			(end -0.12065 -0.2794)
			(stroke
				(width 0.1)
				(type default)
			)
			(layer "B.Fab")
		)
		(fp_line
			(start 0.12065 -0.305054)
			(end 0.12065 -0.2794)
			(stroke
				(width 0.1)
				(type default)
			)
			(layer "B.Fab")
		)
		(fp_line
			(start -0.120396 0.3048)
			(end -0.120396 0.2794)
			(stroke
				(width 0.1)
				(type default)
			)
			(layer "B.Fab")
		)
		(fp_line
			(start -0.120396 0.2794)
			(end 0.12065 0.2794)
			(stroke
				(width 0.1)
				(type default)
			)
			(layer "B.Fab")
		)
		(fp_line
			(start -0.12065 -0.2794)
			(end -0.12065 -0.3048)
			(stroke
				(width 0.1)
				(type default)
			)
			(layer "B.Fab")
		)
		(fp_line
			(start -0.12065 -0.3048)
			(end -0.67945 -0.3048)
			(stroke
				(width 0.1)
				(type default)
			)
			(layer "B.Fab")
		)
		(fp_line
			(start -0.67945 0.3048)
			(end -0.120396 0.3048)
			(stroke
				(width 0.1)
				(type default)
			)
			(layer "B.Fab")
		)
		(fp_line
			(start -0.67945 -0.3048)
			(end -0.67945 0.3048)
			(stroke
				(width 0.1)
				(type default)
			)
			(layer "B.Fab")
		)
		(pad "1" smd circle
			(at 0.40005 0)
			(size 0 0)
			(layers "B.Cu" "B.Mask" "B.Paste")
			(net "I3C_SPD_DDRGL_CPU0_SDA")
		)
		(pad "2" smd circle
			(at -0.40005 0)
			(size 0 0)
			(layers "B.Cu" "B.Mask" "B.Paste")
			(net "I3C_SPD_DDRJ_CPU0_SDA")
		)
	)
)
